(kicad_pcb
	(version 20260206)
	(generator "pcbnew")
	(generator_version "10.0")
	(general
		(thickness 1.6)
		(legacy_teardrops no)
	)
	(paper "A4")
	(title_block
		(title "Wiwynn_Tioga_Pass_MB.brd")
		(comment 1 "Tioga Pass / footprint 2254 of 4770 (U5D1), pads 1965-2073 of 3647")
	)
	(layers
		(0 "F.Cu" signal "TOP")
		(4 "In1.Cu" signal "L2GND")
		(6 "In2.Cu" signal "L3")
		(8 "In3.Cu" signal "L4GND")
		(10 "In4.Cu" signal "L5")
		(12 "In5.Cu" signal "L6GND")
		(14 "In6.Cu" signal "L7VCC")
		(16 "In7.Cu" signal "L8VCC")
		(18 "In8.Cu" signal "L9GND")
		(20 "In9.Cu" signal "L10")
		(22 "In10.Cu" signal "L11GND")
		(24 "In11.Cu" signal "L12")
		(26 "In12.Cu" signal "L13GND")
		(2 "B.Cu" signal "BOTTOM")
		(9 "F.Adhes" user "F.Adhesive")
		(11 "B.Adhes" user "B.Adhesive")
		(13 "F.Paste" user "Package Geometry/Pastemask Top")
		(15 "B.Paste" user "Package Geometry/Pastemask Bottom")
		(5 "F.SilkS" user "Ref Des/Silkscreen Top")
		(7 "B.SilkS" user "Ref Des/Silkscreen Bottom")
		(1 "F.Mask" user "Board Geometry/Soldermask Top")
		(3 "B.Mask" user "Board Geometry/Soldermask Bottom")
		(17 "Dwgs.User" user "User.Drawings")
		(19 "Cmts.User" user "User.Comments")
		(21 "Eco1.User" user "User.Eco1")
		(23 "Eco2.User" user "User.Eco2")
		(25 "Edge.Cuts" user "Board Geometry/Outline")
		(27 "Margin" user)
		(31 "F.CrtYd" user "Package Geometry/Place Bound Top")
		(29 "B.CrtYd" user "Package Geometry/Place Bound Bottom")
		(35 "F.Fab" user "Ref Des/Assembly Top")
		(33 "B.Fab" user "Ref Des/Assembly Bottom")
	)
	(footprint ""
		(layer "F.Cu")
		(at 270.000222 -76.550012 180)
		(property "Reference" "U5D1"
			(at 19.124422 31.601918 0)
			(unlocked yes)
			(layer "F.SilkS")
			(effects
				(font
					(size 0.7874 0.5842)
					(thickness 0.1524)
				)
			)
		)
		(property "Value" ""
			(at 0 0 180)
			(layer "F.Fab")
			(effects
				(font
					(size 1.27 1.27)
				)
			)
		)
		(duplicate_pad_numbers_are_jumpers no)
		(pad "DA50" smd circle
			(at 6.344412 12.720828)
			(size 0.4318 0.4318)
			(layers "F.Cu" "F.Mask" "F.Paste")
			(net "GND")
		)
		(pad "DA52" smd circle
			(at 8.061452 12.720828)
			(size 0.4318 0.4318)
			(layers "F.Cu" "F.Mask" "F.Paste")
			(net "TP_CPU0_RSVD_50")
		)
		(pad "DA54" smd circle
			(at 9.778492 12.720828)
			(size 0.4318 0.4318)
			(layers "F.Cu" "F.Mask" "F.Paste")
			(net "TP_CPU0_RSVD_49")
		)
		(pad "DA56" smd circle
			(at 11.495532 12.720828)
			(size 0.4318 0.4318)
			(layers "F.Cu" "F.Mask" "F.Paste")
			(net "TP_CPU0_RSVD_48")
		)
		(pad "DA58" smd circle
			(at 13.212572 12.720828)
			(size 0.4318 0.4318)
			(layers "F.Cu" "F.Mask" "F.Paste")
			(net "M_F_MA<9>")
		)
		(pad "DA60" smd circle
			(at 14.929612 12.720828)
			(size 0.4318 0.4318)
			(layers "F.Cu" "F.Mask" "F.Paste")
			(net "M_F_MA<11>")
		)
		(pad "DA62" smd circle
			(at 16.646398 12.720828)
			(size 0.4318 0.4318)
			(layers "F.Cu" "F.Mask" "F.Paste")
			(net "M_F_BG<0>")
		)
		(pad "DA64" smd circle
			(at 18.363438 12.720828)
			(size 0.4318 0.4318)
			(layers "F.Cu" "F.Mask" "F.Paste")
			(net "GND")
		)
		(pad "DA66" smd circle
			(at 20.080478 12.720828)
			(size 0.4318 0.4318)
			(layers "F.Cu" "F.Mask" "F.Paste")
			(net "M_D_ECC<6>")
		)
		(pad "DA68" smd circle
			(at 21.797518 12.720828)
			(size 0.4318 0.4318)
			(layers "F.Cu" "F.Mask" "F.Paste")
			(net "M_D_ECC<0>")
		)
		(pad "DA70" smd circle
			(at 23.514558 12.720828)
			(size 0.4318 0.4318)
			(layers "F.Cu" "F.Mask" "F.Paste")
			(net "GND")
		)
		(pad "DA72" smd circle
			(at 25.231598 12.720828)
			(size 0.4318 0.4318)
			(layers "F.Cu" "F.Mask" "F.Paste")
			(net "FM_CPU0_PKGID2")
		)
		(pad "DA74" smd circle
			(at 26.948384 12.720828)
			(size 0.4318 0.4318)
			(layers "F.Cu" "F.Mask" "F.Paste")
			(net "GND")
		)
		(pad "DA76" smd circle
			(at 28.665424 12.720828)
			(size 0.4318 0.4318)
			(layers "F.Cu" "F.Mask" "F.Paste")
			(net "GND")
		)
		(pad "DA78" smd circle
			(at 30.382464 12.720828)
			(size 0.4318 0.4318)
			(layers "F.Cu" "F.Mask" "F.Paste")
			(net "GND")
		)
		(pad "DA80" smd circle
			(at 32.099504 12.720828)
			(size 0.4318 0.4318)
			(layers "F.Cu" "F.Mask" "F.Paste")
			(net "GND")
		)
		(pad "DA82" smd circle
			(at 33.816544 12.720828)
			(size 0.4318 0.4318)
			(layers "F.Cu" "F.Mask" "F.Paste")
			(net "M_E_DQS_DN<1>")
		)
		(pad "DA84" smd circle
			(at 35.533584 12.720828)
			(size 0.4318 0.4318)
			(layers "F.Cu" "F.Mask" "F.Paste")
			(net "M_D_DQ<3>")
		)
		(pad "DA86" smd custom
			(at 37.250624 12.720828 270)
			(size 0.10795 0.10795)
			(layers "F.Cu" "F.Mask" "F.Paste")
			(net "M_D_DQ<2>")
			(options
				(clearance outline)
				(anchor circle)
			)
			(primitives
				(gr_poly
					(pts
						(arc
							(start 0.2159 -0.0381)
							(mid 0 -0.254)
							(end -0.2159 -0.0381)
						)
						(arc
							(start -0.2159 0.0381)
							(mid 0 0.254)
							(end 0.2159 0.0381)
						)
					)
					(width 0)
					(fill yes)
				)
			)
		)
		(pad "DB1" smd custom
			(at -37.250624 15.015972 90)
			(size 0.10795 0.10795)
			(layers "F.Cu" "F.Mask" "F.Paste")
			(net "P3E_CPU0_PE1_SS_TXP<1>")
			(options
				(clearance outline)
				(anchor circle)
			)
			(primitives
				(gr_poly
					(pts
						(arc
							(start 0.2159 -0.0381)
							(mid 0 -0.254)
							(end -0.2159 -0.0381)
						)
						(arc
							(start -0.2159 0.0381)
							(mid 0 0.254)
							(end 0.2159 0.0381)
						)
					)
					(width 0)
					(fill yes)
				)
			)
		)
		(pad "DB3" smd circle
			(at -35.533584 15.015972)
			(size 0.4318 0.4318)
			(layers "F.Cu" "F.Mask" "F.Paste")
			(net "GND")
		)
		(pad "DB5" smd circle
			(at -33.816544 15.015972)
			(size 0.4318 0.4318)
			(layers "F.Cu" "F.Mask" "F.Paste")
			(net "P3E_CPU0_PE3_OCP_TXN<14>")
		)
		(pad "DB7" smd circle
			(at -32.099504 15.015972)
			(size 0.4318 0.4318)
			(layers "F.Cu" "F.Mask" "F.Paste")
			(net "GND")
		)
		(pad "DB9" smd circle
			(at -30.382464 15.015972)
			(size 0.4318 0.4318)
			(layers "F.Cu" "F.Mask" "F.Paste")
			(net "P3E_CPU0_PE1_SS_RXP<2>")
		)
		(pad "DB11" smd circle
			(at -28.665424 15.015972)
			(size 0.4318 0.4318)
			(layers "F.Cu" "F.Mask" "F.Paste")
			(net "P3E_CPU0_PE3_OCP_RXN<13>")
		)
		(pad "DB13" smd circle
			(at -26.948384 15.015972)
			(size 0.4318 0.4318)
			(layers "F.Cu" "F.Mask" "F.Paste")
			(net "GND")
		)
		(pad "DB15" smd circle
			(at -25.231598 15.015972)
			(size 0.4318 0.4318)
			(layers "F.Cu" "F.Mask" "F.Paste")
			(net "TP_CPU0_UPI2_RSVD_CW16")
		)
		(pad "DB17" smd circle
			(at -23.514558 15.015972)
			(size 0.4318 0.4318)
			(layers "F.Cu" "F.Mask" "F.Paste")
			(net "GND")
		)
		(pad "DB19" smd circle
			(at -21.797518 15.015972)
			(size 0.4318 0.4318)
			(layers "F.Cu" "F.Mask" "F.Paste")
			(net "GND")
		)
		(pad "DB21" smd circle
			(at -20.080478 15.015972)
			(size 0.4318 0.4318)
			(layers "F.Cu" "F.Mask" "F.Paste")
			(net "GND")
		)
		(pad "DB23" smd circle
			(at -18.363438 15.015972)
			(size 0.4318 0.4318)
			(layers "F.Cu" "F.Mask" "F.Paste")
			(net "GND")
		)
		(pad "DB25" smd circle
			(at -16.646398 15.015972)
			(size 0.4318 0.4318)
			(layers "F.Cu" "F.Mask" "F.Paste")
			(net "GND")
		)
		(pad "DB27" smd circle
			(at -14.929612 15.015972)
			(size 0.4318 0.4318)
			(layers "F.Cu" "F.Mask" "F.Paste")
			(net "M_F_DQ<59>")
		)
		(pad "DB29" smd circle
			(at -13.212572 15.015972)
			(size 0.4318 0.4318)
			(layers "F.Cu" "F.Mask" "F.Paste")
			(net "M_F_DQS_DP<7>")
		)
		(pad "DB31" smd circle
			(at -11.495532 15.015972)
			(size 0.4318 0.4318)
			(layers "F.Cu" "F.Mask" "F.Paste")
			(net "M_F_DQ<61>")
		)
		(pad "DB33" smd circle
			(at -9.778492 15.015972)
			(size 0.4318 0.4318)
			(layers "F.Cu" "F.Mask" "F.Paste")
			(net "M_F_DQ<51>")
		)
		(pad "DB35" smd circle
			(at -8.061452 15.015972)
			(size 0.4318 0.4318)
			(layers "F.Cu" "F.Mask" "F.Paste")
			(net "M_F_DQS_DP<6>")
		)
		(pad "DB37" smd circle
			(at -6.344412 15.015972)
			(size 0.4318 0.4318)
			(layers "F.Cu" "F.Mask" "F.Paste")
			(net "M_F_DQ<53>")
		)
		(pad "DB39" smd circle
			(at -4.627626 15.015972)
			(size 0.4318 0.4318)
			(layers "F.Cu" "F.Mask" "F.Paste")
			(net "GND")
		)
		(pad "DB41" smd circle
			(at -2.910586 15.015972)
			(size 0.4318 0.4318)
			(layers "F.Cu" "F.Mask" "F.Paste")
			(net "GND")
		)
		(pad "DB45" smd circle
			(at 2.052066 13.215874)
			(size 0.4318 0.4318)
			(layers "F.Cu" "F.Mask" "F.Paste")
			(net "SVID_DIO0_CPU0")
		)
		(pad "DB47" smd circle
			(at 3.769106 13.215874)
			(size 0.4318 0.4318)
			(layers "F.Cu" "F.Mask" "F.Paste")
			(net "GND")
		)
		(pad "DB49" smd circle
			(at 5.485892 13.215874)
			(size 0.4318 0.4318)
			(layers "F.Cu" "F.Mask" "F.Paste")
			(net "GND")
		)
		(pad "DB51" smd circle
			(at 7.202932 13.215874)
			(size 0.4318 0.4318)
			(layers "F.Cu" "F.Mask" "F.Paste")
			(net "PD_CPU0_TEST13")
		)
		(pad "DB53" smd circle
			(at 8.919972 13.215874)
			(size 0.4318 0.4318)
			(layers "F.Cu" "F.Mask" "F.Paste")
			(net "PVDDQ_DEF")
		)
		(pad "DB55" smd circle
			(at 10.637012 13.215874)
			(size 0.4318 0.4318)
			(layers "F.Cu" "F.Mask" "F.Paste")
			(net "PVDDQ_DEF")
		)
		(pad "DB57" smd circle
			(at 12.354052 13.215874)
			(size 0.4318 0.4318)
			(layers "F.Cu" "F.Mask" "F.Paste")
			(net "PVDDQ_DEF")
		)
		(pad "DB59" smd circle
			(at 14.071092 13.215874)
			(size 0.4318 0.4318)
			(layers "F.Cu" "F.Mask" "F.Paste")
			(net "PVDDQ_DEF")
		)
		(pad "DB61" smd circle
			(at 15.787878 13.215874)
			(size 0.4318 0.4318)
			(layers "F.Cu" "F.Mask" "F.Paste")
			(net "PVDDQ_DEF")
		)
		(pad "DB63" smd circle
			(at 17.504918 13.215874)
			(size 0.4318 0.4318)
			(layers "F.Cu" "F.Mask" "F.Paste")
			(net "PVDDQ_DEF")
		)
		(pad "DB65" smd circle
			(at 19.221958 13.215874)
			(size 0.4318 0.4318)
			(layers "F.Cu" "F.Mask" "F.Paste")
			(net "M_D_ECC<2>")
		)
		(pad "DB67" smd circle
			(at 20.938998 13.215874)
			(size 0.4318 0.4318)
			(layers "F.Cu" "F.Mask" "F.Paste")
			(net "M_D_DQS_DN<17>")
		)
		(pad "DB69" smd circle
			(at 22.656038 13.215874)
			(size 0.4318 0.4318)
			(layers "F.Cu" "F.Mask" "F.Paste")
			(net "M_D_ECC<4>")
		)
		(pad "DB71" smd circle
			(at 24.373078 13.215874)
			(size 0.4318 0.4318)
			(layers "F.Cu" "F.Mask" "F.Paste")
			(net "FM_CPU0_PROC_ID1")
		)
		(pad "DB73" smd circle
			(at 26.090118 13.215874)
			(size 0.4318 0.4318)
			(layers "F.Cu" "F.Mask" "F.Paste")
			(net "GND")
		)
		(pad "DB75" smd circle
			(at 27.806904 13.215874)
			(size 0.4318 0.4318)
			(layers "F.Cu" "F.Mask" "F.Paste")
			(net "M_F_DQ<13>")
		)
		(pad "DB77" smd circle
			(at 29.523944 13.215874)
			(size 0.4318 0.4318)
			(layers "F.Cu" "F.Mask" "F.Paste")
			(net "GND")
		)
		(pad "DB79" smd circle
			(at 31.240984 13.215874)
			(size 0.4318 0.4318)
			(layers "F.Cu" "F.Mask" "F.Paste")
			(net "M_E_DQ<8>")
		)
		(pad "DB81" smd circle
			(at 32.958024 13.215874)
			(size 0.4318 0.4318)
			(layers "F.Cu" "F.Mask" "F.Paste")
			(net "M_E_DQS_DP<1>")
		)
		(pad "DB83" smd circle
			(at 34.675064 13.215874)
			(size 0.4318 0.4318)
			(layers "F.Cu" "F.Mask" "F.Paste")
			(net "GND")
		)
		(pad "DB85" smd circle
			(at 36.392104 13.215874)
			(size 0.4318 0.4318)
			(layers "F.Cu" "F.Mask" "F.Paste")
			(net "GND")
		)
		(pad "DC2" smd custom
			(at -36.392104 15.511526 90)
			(size 0.10795 0.10795)
			(layers "F.Cu" "F.Mask" "F.Paste")
			(net "P3E_CPU0_PE1_SS_TXN<1>")
			(options
				(clearance outline)
				(anchor circle)
			)
			(primitives
				(gr_poly
					(pts
						(arc
							(start 0.2159 -0.0381)
							(mid 0 -0.254)
							(end -0.2159 -0.0381)
						)
						(arc
							(start -0.2159 0.0381)
							(mid 0 0.254)
							(end 0.2159 0.0381)
						)
					)
					(width 0)
					(fill yes)
				)
			)
		)
		(pad "DC4" smd circle
			(at -34.675064 15.511526)
			(size 0.4318 0.4318)
			(layers "F.Cu" "F.Mask" "F.Paste")
			(net "P3E_CPU0_PE1_SS_TXP<3>")
		)
		(pad "DC6" smd circle
			(at -32.958024 15.511526)
			(size 0.4318 0.4318)
			(layers "F.Cu" "F.Mask" "F.Paste")
			(net "P3E_CPU0_PE3_OCP_TXP<13>")
		)
		(pad "DC8" smd circle
			(at -31.240984 15.511526)
			(size 0.4318 0.4318)
			(layers "F.Cu" "F.Mask" "F.Paste")
			(net "P3E_CPU0_PE1_SS_RXN<2>")
		)
		(pad "DC10" smd circle
			(at -29.523944 15.511526)
			(size 0.4318 0.4318)
			(layers "F.Cu" "F.Mask" "F.Paste")
			(net "P3E_CPU0_PE1_SS_RXN<3>")
		)
		(pad "DC12" smd circle
			(at -27.806904 15.511526)
			(size 0.4318 0.4318)
			(layers "F.Cu" "F.Mask" "F.Paste")
			(net "P3E_CPU0_PE3_OCP_RXP<12>")
		)
		(pad "DC14" smd circle
			(at -26.090118 15.511526)
			(size 0.4318 0.4318)
			(layers "F.Cu" "F.Mask" "F.Paste")
			(net "GND")
		)
		(pad "DC16" smd circle
			(at -24.373078 15.511526)
			(size 0.4318 0.4318)
			(layers "F.Cu" "F.Mask" "F.Paste")
			(net "TP_CPU0_UPI2_RSVD_DA16")
		)
		(pad "DC18" smd circle
			(at -22.656038 15.511526)
			(size 0.4318 0.4318)
			(layers "F.Cu" "F.Mask" "F.Paste")
			(net "PVCCIO_CPU0")
		)
		(pad "DC20" smd circle
			(at -20.938998 15.511526)
			(size 0.4318 0.4318)
			(layers "F.Cu" "F.Mask" "F.Paste")
			(net "GND")
		)
		(pad "DC22" smd circle
			(at -19.221958 15.511526)
			(size 0.4318 0.4318)
			(layers "F.Cu" "F.Mask" "F.Paste")
			(net "GND")
		)
		(pad "DC24" smd circle
			(at -17.504918 15.511526)
			(size 0.4318 0.4318)
			(layers "F.Cu" "F.Mask" "F.Paste")
			(net "GND")
		)
		(pad "DC26" smd circle
			(at -15.787878 15.511526)
			(size 0.4318 0.4318)
			(layers "F.Cu" "F.Mask" "F.Paste")
			(net "GND")
		)
		(pad "DC28" smd circle
			(at -14.071092 15.511526)
			(size 0.4318 0.4318)
			(layers "F.Cu" "F.Mask" "F.Paste")
			(net "M_F_DQ<63>")
		)
		(pad "DC30" smd circle
			(at -12.354052 15.511526)
			(size 0.4318 0.4318)
			(layers "F.Cu" "F.Mask" "F.Paste")
			(net "M_F_DQ<57>")
		)
		(pad "DC32" smd circle
			(at -10.637012 15.511526)
			(size 0.4318 0.4318)
			(layers "F.Cu" "F.Mask" "F.Paste")
			(net "GND")
		)
		(pad "DC34" smd circle
			(at -8.919972 15.511526)
			(size 0.4318 0.4318)
			(layers "F.Cu" "F.Mask" "F.Paste")
			(net "M_F_DQ<55>")
		)
		(pad "DC36" smd circle
			(at -7.202932 15.511526)
			(size 0.4318 0.4318)
			(layers "F.Cu" "F.Mask" "F.Paste")
			(net "M_F_DQ<49>")
		)
		(pad "DC38" smd circle
			(at -5.485892 15.511526)
			(size 0.4318 0.4318)
			(layers "F.Cu" "F.Mask" "F.Paste")
			(net "GND")
		)
		(pad "DC40" smd circle
			(at -3.769106 15.511526)
			(size 0.4318 0.4318)
			(layers "F.Cu" "F.Mask" "F.Paste")
			(net "M_F_DQS_DP<13>")
		)
		(pad "DC42" smd circle
			(at -2.052066 15.511526)
			(size 0.4318 0.4318)
			(layers "F.Cu" "F.Mask" "F.Paste")
			(net "GND")
		)
		(pad "DC44" smd circle
			(at 1.193546 13.711428)
			(size 0.508 0.508)
			(layers "F.Cu" "F.Mask" "F.Paste")
			(net "SVID_CLK0_CPU0")
		)
		(pad "DC46" smd circle
			(at 2.910586 13.711428)
			(size 0.4318 0.4318)
			(layers "F.Cu" "F.Mask" "F.Paste")
			(net "TP_CPU0_RSVD_47")
		)
		(pad "DC48" smd circle
			(at 4.627626 13.711428)
			(size 0.4318 0.4318)
			(layers "F.Cu" "F.Mask" "F.Paste")
			(net "A_CPU0_DEF_RCOMP0")
		)
		(pad "DC50" smd circle
			(at 6.344412 13.711428)
			(size 0.4318 0.4318)
			(layers "F.Cu" "F.Mask" "F.Paste")
			(net "PD_CPU0_TEST14")
		)
		(pad "DC52" smd circle
			(at 8.061452 13.711428)
			(size 0.4318 0.4318)
			(layers "F.Cu" "F.Mask" "F.Paste")
			(net "TP_CPU0_RSVD_46")
		)
		(pad "DC54" smd circle
			(at 9.778492 13.711428)
			(size 0.4318 0.4318)
			(layers "F.Cu" "F.Mask" "F.Paste")
			(net "M_F_MA<15>")
		)
		(pad "DC56" smd circle
			(at 11.495532 13.711428)
			(size 0.4318 0.4318)
			(layers "F.Cu" "F.Mask" "F.Paste")
			(net "M_F_BA<1>")
		)
		(pad "DC58" smd circle
			(at 13.212572 13.711428)
			(size 0.4318 0.4318)
			(layers "F.Cu" "F.Mask" "F.Paste")
			(net "M_F_MA<1>")
		)
		(pad "DC60" smd circle
			(at 14.929612 13.711428)
			(size 0.4318 0.4318)
			(layers "F.Cu" "F.Mask" "F.Paste")
			(net "M_F_MA<7>")
		)
		(pad "DC62" smd circle
			(at 16.646398 13.711428)
			(size 0.4318 0.4318)
			(layers "F.Cu" "F.Mask" "F.Paste")
			(net "M_F_ACT_N")
		)
		(pad "DC64" smd circle
			(at 18.363438 13.711428)
			(size 0.4318 0.4318)
			(layers "F.Cu" "F.Mask" "F.Paste")
			(net "GND")
		)
		(pad "DC66" smd circle
			(at 20.080478 13.711428)
			(size 0.4318 0.4318)
			(layers "F.Cu" "F.Mask" "F.Paste")
			(net "GND")
		)
		(pad "DC68" smd circle
			(at 21.797518 13.711428)
			(size 0.4318 0.4318)
			(layers "F.Cu" "F.Mask" "F.Paste")
			(net "GND")
		)
		(pad "DC70" smd circle
			(at 23.514558 13.711428)
			(size 0.4318 0.4318)
			(layers "F.Cu" "F.Mask" "F.Paste")
			(net "GND")
		)
		(pad "DC72" smd circle
			(at 25.231598 13.711428)
			(size 0.4318 0.4318)
			(layers "F.Cu" "F.Mask" "F.Paste")
			(net "FM_CPU0_PKGID0")
		)
		(pad "DC74" smd circle
			(at 26.948384 13.711428)
			(size 0.4318 0.4318)
			(layers "F.Cu" "F.Mask" "F.Paste")
			(net "M_F_DQ<12>")
		)
		(pad "DC76" smd circle
			(at 28.665424 13.711428)
			(size 0.4318 0.4318)
			(layers "F.Cu" "F.Mask" "F.Paste")
			(net "M_F_DQ<9>")
		)
		(pad "DC78" smd circle
			(at 30.382464 13.711428)
			(size 0.4318 0.4318)
			(layers "F.Cu" "F.Mask" "F.Paste")
			(net "GND")
		)
		(pad "DC80" smd circle
			(at 32.099504 13.711428)
			(size 0.4318 0.4318)
			(layers "F.Cu" "F.Mask" "F.Paste")
			(net "M_E_DQS_DN<10>")
		)
		(pad "DC82" smd circle
			(at 33.816544 13.711428)
			(size 0.4318 0.4318)
			(layers "F.Cu" "F.Mask" "F.Paste")
			(net "M_E_DQ<14>")
		)
		(pad "DC84" smd circle
			(at 35.533584 13.711428)
			(size 0.4318 0.4318)
			(layers "F.Cu" "F.Mask" "F.Paste")
			(net "GND")
		)
		(pad "DC86" smd custom
			(at 37.250624 13.711428 270)
			(size 0.10795 0.10795)
			(layers "F.Cu" "F.Mask" "F.Paste")
			(net "GND")
			(options
				(clearance outline)
				(anchor circle)
			)
			(primitives
				(gr_poly
					(pts
						(arc
							(start 0.2159 -0.0381)
							(mid 0 -0.254)
							(end -0.2159 -0.0381)
						)
						(arc
							(start -0.2159 0.0381)
							(mid 0 0.254)
							(end 0.2159 0.0381)
						)
					)
					(width 0)
					(fill yes)
				)
			)
		)
		(pad "DD3" smd circle
			(at -35.533584 16.006572)
			(size 0.4318 0.4318)
			(layers "F.Cu" "F.Mask" "F.Paste")
			(net "P3E_CPU0_PE1_SS_TXP<2>")
		)
		(pad "DD5" smd circle
			(at -33.816544 16.006572)
			(size 0.4318 0.4318)
			(layers "F.Cu" "F.Mask" "F.Paste")
			(net "P3E_CPU0_PE3_OCP_TXN<13>")
		)
		(pad "DD7" smd circle
			(at -32.099504 16.006572)
			(size 0.4318 0.4318)
			(layers "F.Cu" "F.Mask" "F.Paste")
			(net "PVCCIO_CPU0")
		)
		(pad "DD9" smd circle
			(at -30.382464 16.006572)
			(size 0.4318 0.4318)
			(layers "F.Cu" "F.Mask" "F.Paste")
			(net "P3E_CPU0_PE1_SS_RXP<4>")
		)
		(pad "DD11" smd circle
			(at -28.665424 16.006572)
			(size 0.4318 0.4318)
			(layers "F.Cu" "F.Mask" "F.Paste")
			(net "GND")
		)
	)
)
